FILE_TYPE = MULTI_PHYS_TABLE;

PART 'Q_DIODE'

{========================================================================================}
:VALUE           | PACK_TYPE | MATERIAL | PART_NUMBER        = STANDARD        | LIFECYCLE      | PART_NUMBER   | JEDEC_TYPE        | CLASS | DESCRIPTION                                | COMPONENT_TYPE | LEAD_LENGTH | LPID | DAY        ;
{========================================================================================}
 'CH751H-40PT'   | 'SMLF'    | 'IC'     | 'TMP_QBC000751Z05'(!) = 'End of Design' | 'End of Life'  | 'BC000751Z05' |'SOD323_EOL'| 'IC'  | 'DIODE SMD CH751H-40PT(40V,30MA)'          | 'SMALLSMT'     | ''          | ''   | ''        
 'CH751H-40PT'   | 'SMLF'    | 'EMPTY'  | 'TMP_QBC000751Z05'(!) = 'End of Design' | 'End of Life'  | 'BC000751Z05' |'SOD323_EOL'| 'IO'  | 'DIODE SMD CH751H-40PT(40V,30MA)'          | 'SMALLSMT'     | ''          | ''   | ''        
 '1N4448WS-7-F'  | 'SMLF'    | 'IC'     | 'TMP_QBC004448Z64'(!) = 'End of Design' | 'Comp-Approve' | 'BC004448Z64' |'SOD323'| 'IC'  | 'DIODE SMD 1N4448WS-7-F(100V,250MA)SOD323' | 'SMALLSMT'     | ''          | ''   | ''        
 '1N4448WS-7-F'  | 'SMLF'    | 'EMPTY'  | 'TMP_QBC004448Z64'(!) = 'End of Design' | 'Comp-Approve' | 'BC004448Z64' |'SOD323'| 'IO'  | 'DIODE SMD 1N4448WS-7-F(100V,250MA)SOD323' | 'SMALLSMT'     | ''          | ''   | ''        
 '1N4148WS-7-F'  | 'SMLF'    | 'IC'     | 'TMP_QBC004148Z79'(!) = 'End of Design'  | 'Comp-Approve'   | 'BC004148Z79' |'SOD323'| 'IC'  | 'DIODE SMD 1N4148WS-7-F(75V,150MA)'        | 'SMALLSMT'     | ''          | ''   | ''        
 '1N4148WS-7-F'  | 'SMLF'    | 'EMPTY'  | 'TMP_QBC004148Z79'(!) = 'End of Design'  | 'Comp-Approve'   | 'BC004148Z79' |'SOD323'| 'IO'  | 'DIODE SMD 1N4148WS-7-F(75V,150MA)'        | 'SMALLSMT'     | ''          | ''   | ''        
 'SL42-E3/57T'   | 'SMLF'    | 'IC'     | 'BC00SL42Z00'(!)   = ''              | 'End of Life'  | 'BC00SL42Z00' |'D2723_SMCXB_EOL'| 'IC'  | 'DIODE SMD SL42-E3/57T(20V,4A)SMC'         | 'SMALLSMT'     | ''          | ''   | ''        
 'SL42-E3/57T'   | 'SMLF'    | 'EMPTY'  | 'BC00SL42Z00'(!)   = ''              | 'End of Life'  | 'BC00SL42Z00' |'D2723_SMCXB_EOL'| 'IO'  | 'DIODE SMD SL42-E3/57T(20V,4A)SMC'         | 'SMALLSMT'     | ''          | ''   | ''        
 'SDMK0340L-7-F' | 'SMLF'    | 'IC'     | 'BC000340033'(!)   = ''              | ''             | 'BC000340033' |'SOD323XB'| 'IC'  | 'DIODE SMD SDMK0340L-7-F(40V,30MA)'        | 'SMALLSMT'     | ''          | ''   | '20101005'
 'SDMK0340L-7-F' | 'SMLF'    | 'EMPTY'  | 'BC000340033'(!)   = ''              | ''             | 'BC000340033' |'SOD323XB'| 'IO'  | 'DIODE SMD SDMK0340L-7-F(40V,30MA)'        | 'SMALLSMT'     | ''          | ''   | '20101005'
 'RB751V-40'     | 'SMLF'    | 'IC'     | 'BCRB751VZ16'(!)   = 'End of Design' | 'Comp-Approve' | 'BCRB751VZ16' |'SOD323'| 'IC'  | 'DIODE SMD RB751V-40(40V,30MA)'            | 'SMALLSMT'     | ''          | ''   | '20101123'
 'RB751V-40'     | 'SMLF'    | 'EMPTY'  | 'BCRB751VZ16'(!)   = 'End of Design' | 'Comp-Approve' | 'BCRB751VZ16' |'SOD323'| 'IO'  | 'DIODE SMD RB751V-40(40V,30MA)'            | 'SMALLSMT'     | ''          | ''   | '20101123'
 'BAS20HT1G'     | 'SMLF'    | 'IC'     | 'BC20HT1GZ00'(!)   = 'End of Design' | 'Comp-Approve' | 'BC20HT1GZ00' |'SOD323XG'| 'IC'  | 'DIODE SMD BAS20HT1G(200V,200MA)'          | 'SMALLSMT'     | ''          | ''   | '20130110'
 'BAS20HT1G'     | 'SMLF'    | 'EMPTY'  | 'BC20HT1GZ00'(!)   = 'End of Design' | 'Comp-Approve' | 'BC20HT1GZ00' |'SOD323XG'| 'IO'  | 'DIODE SMD BAS20HT1G(200V,200MA)'          | 'SMALLSMT'     | ''          | ''   | '20130110'
 '1N4148W-7-F'   | 'SMLF'    | 'IC'     | 'BC004148ZA0'(!)   = ''              | ''             | 'BC004148ZA0' |'SOD123'| 'IC'  | 'DIODE 1N4148W-7-F(75V.150MA)'             | 'SMALLSMT'     | ''          | ''   | '20140708'
 '1N4148W-7-F'   | 'SMLF'    | 'EMPTY'  | 'BC004148ZA0'(!)   = ''              | ''             | 'BC004148ZA0' |'SOD123'| 'IO'  | 'DIODE 1N4148W-7-F(75V.150MA)'             | 'SMALLSMT'     | ''          | ''   | '20140708'
 'BAV21W-7-F'    | 'SMLF'    | 'IC'     | 'BC00021WZ00'(!)   = ''              | ''             | 'BC00021WZ00' |'SOD123XC'| 'IC'  | 'DIODE SMD BAV21W-7-F(250V,0.4A)SOD-123'   | 'SMALLSMT'     | ''          | ''   | '20140801'
 'BAV21W-7-F'    | 'SMLF'    | 'EMPTY'  | 'BC00021WZ00'(!)   = ''              | ''             | 'BC00021WZ00' |'SOD123XC'| 'IO'  | 'DIODE SMD BAV21W-7-F(250V,0.4A)SOD-123'   | 'SMALLSMT'     | ''          | ''   | '20140801'
 'MMBD4148TS'    | 'SMLF'    | 'IC'     | 'BCBD4148Z03'(!)   = ''              | ''             | 'BCBD4148Z03' |'SOD523XE'| 'IC'  | 'DIODE SMD MMBD4148TS(75V,150MA)SOD523'    | 'SMALLSMT'     | ''          | ''   | '20150107'
 'MMBD4148TS'    | 'SMLF'    | 'EMPTY'  | 'BCBD4148Z03'(!)   = ''              | ''             | 'BCBD4148Z03' |'SOD523XE'| 'IO'  | 'DIODE SMD MMBD4148TS(75V,150MA)SOD523'    | 'SMALLSMT'     | ''          | ''   | '20150107'

END_PART

END.

